# T6G (Grand Teton) — schematic netlist excerpt (pin names and nets, part order shuffled) for the footprints in the layout excerpt that follows; sources: Cadence DE-HDL packaged netlist, KiCad conversion of 04192023_DAF0TMB3IC0_F0TG_MB_C_brd_V02_OCP.brd

C1017  Q_CAP  1UF 4V 20% X6S  pkg 0201  page 312 : A = P0V9_CPU0_RT3_2A ; B = GND
R3214  Q_RES  0 5% EMPTY  pkg 0402LF  page 138 : A = NCSI_BMC_TXD0_R1 ; B = RMII_BMC_OCP_TXD_0
C1083  Q_CAP  100PF 50V 5% EMPTY  pkg 0402  page 258 : A = P1V8_CPU1_RT_1D_ADC_MAM ; B = GND

(kicad_pcb
	(version 20260206)
	(generator "pcbnew")
	(generator_version "10.0")
	(general
		(thickness 1.6)
		(legacy_teardrops no)
	)
	(paper "A4")
	(title_block
		(title "04192023_DAF0TMB3IC0_F0TG_MB_C_brd_V02_OCP.brd")
		(comment 1 "Grand Teton / footprints 6308-6310 of 8354")
	)
	(layers
		(0 "F.Cu" signal "TOP")
		(4 "In1.Cu" signal "GND")
		(6 "In2.Cu" signal "IN1")
		(8 "In3.Cu" signal "GND1")
		(10 "In4.Cu" signal "IN2")
		(12 "In5.Cu" signal "GND2")
		(14 "In6.Cu" signal "IN3")
		(16 "In7.Cu" signal "GND3")
		(18 "In8.Cu" signal "VCC")
		(20 "In9.Cu" signal "VCC1")
		(22 "In10.Cu" signal "GND4")
		(24 "In11.Cu" signal "IN4")
		(26 "In12.Cu" signal "GND5")
		(28 "In13.Cu" signal "IN5")
		(30 "In14.Cu" signal "GND6")
		(32 "In15.Cu" signal "IN6")
		(34 "In16.Cu" signal "GND7")
		(2 "B.Cu" signal "BOTTOM")
		(9 "F.Adhes" user "F.Adhesive")
		(11 "B.Adhes" user "B.Adhesive")
		(13 "F.Paste" user "Package Geometry/Pastemask Top")
		(15 "B.Paste" user "Package Geometry/Pastemask Bottom")
		(5 "F.SilkS" user "Ref Des/Silkscreen Top")
		(7 "B.SilkS" user "Ref Des/Silkscreen Bottom")
		(1 "F.Mask" user "Board Geometry/Soldermask Top")
		(3 "B.Mask" user "Board Geometry/Soldermask Bottom")
		(17 "Dwgs.User" user "User.Drawings")
		(19 "Cmts.User" user "User.Comments")
		(21 "Eco1.User" user "User.Eco1")
		(23 "Eco2.User" user "User.Eco2")
		(25 "Edge.Cuts" user "Board Geometry/Outline")
		(27 "Margin" user)
		(31 "F.CrtYd" user "Package Geometry/Place Bound Top")
		(29 "B.CrtYd" user "Package Geometry/Place Bound Bottom")
		(35 "F.Fab" user "Ref Des/Assembly Top")
		(33 "B.Fab" user "Ref Des/Assembly Bottom")
	)
	(footprint ""
		(layer "B.Cu")
		(at 205.375256 -70.31228 180)
		(property "Reference" "R3214"
			(at 0 0 0)
			(layer "B.SilkS")
			(hide yes)
			(effects
				(font
					(size 1.27 1.27)
				)
				(justify mirror)
			)
		)
		(property "Value" ""
			(at 0 0 0)
			(layer "B.Fab")
			(effects
				(font
					(size 1.27 1.27)
				)
				(justify mirror)
			)
		)
		(duplicate_pad_numbers_are_jumpers no)
		(fp_line
			(start 0.7874 0.4064)
			(end 0.7874 -0.4064)
			(stroke
				(width 0.1524)
				(type default)
			)
			(layer "B.SilkS")
		)
		(fp_line
			(start 0.7874 -0.4064)
			(end -0.7874 -0.4064)
			(stroke
				(width 0.1524)
				(type default)
			)
			(layer "B.SilkS")
		)
		(fp_line
			(start -0.7874 0.4064)
			(end 0.7874 0.4064)
			(stroke
				(width 0.1524)
				(type default)
			)
			(layer "B.SilkS")
		)
		(fp_line
			(start -0.7874 -0.4064)
			(end -0.7874 0.4064)
			(stroke
				(width 0.1524)
				(type default)
			)
			(layer "B.SilkS")
		)
		(fp_line
			(start 0.67945 0.3048)
			(end 0.67945 -0.305054)
			(stroke
				(width 0.1)
				(type default)
			)
			(layer "B.Fab")
		)
		(fp_line
			(start 0.67945 -0.305054)
			(end 0.12065 -0.305054)
			(stroke
				(width 0.1)
				(type default)
			)
			(layer "B.Fab")
		)
		(fp_line
			(start 0.12065 0.3048)
			(end 0.67945 0.3048)
			(stroke
				(width 0.1)
				(type default)
			)
			(layer "B.Fab")
		)
		(fp_line
			(start 0.12065 0.2794)
			(end 0.12065 0.3048)
			(stroke
				(width 0.1)
				(type default)
			)
			(layer "B.Fab")
		)
		(fp_line
			(start 0.12065 -0.2794)
			(end -0.12065 -0.2794)
			(stroke
				(width 0.1)
				(type default)
			)
			(layer "B.Fab")
		)
		(fp_line
			(start 0.12065 -0.305054)
			(end 0.12065 -0.2794)
			(stroke
				(width 0.1)
				(type default)
			)
			(layer "B.Fab")
		)
		(fp_line
			(start -0.120396 0.3048)
			(end -0.120396 0.2794)
			(stroke
				(width 0.1)
				(type default)
			)
			(layer "B.Fab")
		)
		(fp_line
			(start -0.120396 0.2794)
			(end 0.12065 0.2794)
			(stroke
				(width 0.1)
				(type default)
			)
			(layer "B.Fab")
		)
		(fp_line
			(start -0.12065 -0.2794)
			(end -0.12065 -0.3048)
			(stroke
				(width 0.1)
				(type default)
			)
			(layer "B.Fab")
		)
		(fp_line
			(start -0.12065 -0.3048)
			(end -0.67945 -0.3048)
			(stroke
				(width 0.1)
				(type default)
			)
			(layer "B.Fab")
		)
		(fp_line
			(start -0.67945 0.3048)
			(end -0.120396 0.3048)
			(stroke
				(width 0.1)
				(type default)
			)
			(layer "B.Fab")
		)
		(fp_line
			(start -0.67945 -0.3048)
			(end -0.67945 0.3048)
			(stroke
				(width 0.1)
				(type default)
			)
			(layer "B.Fab")
		)
		(pad "1" smd circle
			(at 0.40005 0)
			(size 0 0)
			(layers "B.Cu" "B.Mask" "B.Paste")
			(net "NCSI_BMC_TXD0_R1")
		)
		(pad "2" smd circle
			(at -0.40005 0)
			(size 0 0)
			(layers "B.Cu" "B.Mask" "B.Paste")
			(net "RMII_BMC_OCP_TXD_0")
		)
	)
	(footprint ""
		(layer "B.Cu")
		(at 370.478558 -395.148562 90)
		(property "Reference" "C1017"
			(at 0 0 90)
			(layer "B.SilkS")
			(hide yes)
			(effects
				(font
					(size 1.27 1.27)
				)
				(justify mirror)
			)
		)
		(property "Value" ""
			(at 0 0 90)
			(layer "B.Fab")
			(effects
				(font
					(size 1.27 1.27)
				)
				(justify mirror)
			)
		)
		(duplicate_pad_numbers_are_jumpers no)
		(fp_line
			(start 0.299974 -0.150114)
			(end -0.299974 -0.150114)
			(stroke
				(width 0.1)
				(type default)
			)
			(layer "B.Fab")
		)
		(fp_line
			(start -0.299974 -0.150114)
			(end -0.299974 0.150114)
			(stroke
				(width 0.1)
				(type default)
			)
			(layer "B.Fab")
		)
		(fp_line
			(start 0.299974 0.150114)
			(end 0.299974 -0.150114)
			(stroke
				(width 0.1)
				(type default)
			)
			(layer "B.Fab")
		)
		(fp_line
			(start -0.299974 0.150114)
			(end 0.299974 0.150114)
			(stroke
				(width 0.1)
				(type default)
			)
			(layer "B.Fab")
		)
		(pad "1" smd rect
			(at 0.2667 0 270)
			(size 0.3048 0.381)
			(layers "B.Cu" "B.Mask" "B.Paste")
			(net "P0V9_CPU0_RT3_2A")
		)
		(pad "2" smd rect
			(at -0.2667 0 270)
			(size 0.3048 0.381)
			(layers "B.Cu" "B.Mask" "B.Paste")
			(net "GND")
		)
	)
	(footprint ""
		(layer "B.Cu")
		(at 243.713 -321.818)
		(property "Reference" "C1083"
			(at 0 0 0)
			(layer "B.SilkS")
			(hide yes)
			(effects
				(font
					(size 1.27 1.27)
				)
				(justify mirror)
			)
		)
		(property "Value" ""
			(at 0 0 0)
			(layer "B.Fab")
			(effects
				(font
					(size 1.27 1.27)
				)
				(justify mirror)
			)
		)
		(duplicate_pad_numbers_are_jumpers no)
		(fp_line
			(start -0.7874 -0.4064)
			(end -0.7874 0.4064)
			(stroke
				(width 0.1524)
				(type default)
			)
			(layer "B.SilkS")
		)
		(fp_line
			(start -0.7874 0.4064)
			(end 0.7874 0.4064)
			(stroke
				(width 0.1524)
				(type default)
			)
			(layer "B.SilkS")
		)
		(fp_line
			(start 0.7874 -0.4064)
			(end -0.7874 -0.4064)
			(stroke
				(width 0.1524)
				(type default)
			)
			(layer "B.SilkS")
		)
		(fp_line
			(start 0.7874 0.4064)
			(end 0.7874 -0.4064)
			(stroke
				(width 0.1524)
				(type default)
			)
			(layer "B.SilkS")
		)
		(fp_line
			(start -0.67945 -0.3048)
			(end -0.67945 0.3048)
			(stroke
				(width 0.1)
				(type default)
			)
			(layer "B.Fab")
		)
		(fp_line
			(start -0.67945 0.3048)
			(end -0.120396 0.3048)
			(stroke
				(width 0.1)
				(type default)
			)
			(layer "B.Fab")
		)
		(fp_line
			(start -0.12065 -0.3048)
			(end -0.67945 -0.3048)
			(stroke
				(width 0.1)
				(type default)
			)
			(layer "B.Fab")
		)
		(fp_line
			(start -0.12065 -0.2794)
			(end -0.12065 -0.3048)
			(stroke
				(width 0.1)
				(type default)
			)
			(layer "B.Fab")
		)
		(fp_line
			(start -0.120396 0.2794)
			(end 0.12065 0.2794)
			(stroke
				(width 0.1)
				(type default)
			)
			(layer "B.Fab")
		)
		(fp_line
			(start -0.120396 0.3048)
			(end -0.120396 0.2794)
			(stroke
				(width 0.1)
				(type default)
			)
			(layer "B.Fab")
		)
		(fp_line
			(start 0.12065 -0.305054)
			(end 0.12065 -0.2794)
			(stroke
				(width 0.1)
				(type default)
			)
			(layer "B.Fab")
		)
		(fp_line
			(start 0.12065 -0.2794)
			(end -0.12065 -0.2794)
			(stroke
				(width 0.1)
				(type default)
			)
			(layer "B.Fab")
		)
		(fp_line
			(start 0.12065 0.2794)
			(end 0.12065 0.3048)
			(stroke
				(width 0.1)
				(type default)
			)
			(layer "B.Fab")
		)
		(fp_line
			(start 0.12065 0.3048)
			(end 0.67945 0.3048)
			(stroke
				(width 0.1)
				(type default)
			)
			(layer "B.Fab")
		)
		(fp_line
			(start 0.67945 -0.305054)
			(end 0.12065 -0.305054)
			(stroke
				(width 0.1)
				(type default)
			)
			(layer "B.Fab")
		)
		(fp_line
			(start 0.67945 0.3048)
			(end 0.67945 -0.305054)
			(stroke
				(width 0.1)
				(type default)
			)
			(layer "B.Fab")
		)
		(pad "1" smd circle
			(at 0.40005 0 180)
			(size 0 0)
			(layers "B.Cu" "B.Mask" "B.Paste")
			(net "P1V8_CPU1_RT_1D_ADC_MAM")
		)
		(pad "2" smd circle
			(at -0.40005 0 180)
			(size 0 0)
			(layers "B.Cu" "B.Mask" "B.Paste")
			(net "GND")
		)
	)
)
